FILE_TYPE = CONNECTIVITY;
{Allegro Design Entry HDL 17.2-2016 S066 (3851973) 4/6/2020}
"PAGE_NUMBER" = 162;
0"NC";
1"FPGA_IN_LM75B_INT1_N";
2"FPGA_IN_LM75B_INT2_N";
3"FPGA_IO_6";
4"FPGA_IO_2";
5"FPGA_IO_1";
6"FPGA_IO_0";
7"FPGA_IO_4";
8"FPGA_IO_3";
9"SMA3_SIG_IN_BF_EN_N";
10"FPGA_IO_7";
11"FPGA_IN_LM75B_INT3_N";
12"FPGA_BRD_REV2";
13"FPGA_BRD_REV1";
14"FPGA_IN_RST_DLY_N";
15"FPGA_IN_SHT3X_ALERT_N";
16"FPGA_OUT_SHT3X_RST_N";
17"SMA1_SIG_OUT_BF_EN_N";
18"SMA3_SIG_OUT_BF_EN_N";
19"FPGA_IO_5";
20"SMA2_SIG_OUT_BF_EN_N";
21"SMA1_SIG_IN_BF_EN_N";
22"SMA2_SIG_IN_BF_EN_N";
23"FPGA_OUT_BNO080_BOOT_N";
24"FPGA_OUT_I2C_BUFFER_EN";
25"FPGA_IN_MAC_USB_OC_N";
26"RSVD_DBG_USB_MUX_SEL";
27"IO_L20P_16";
28"IO_L20N_16";
29"IO_L21P_16";
30"IO_L21N_16";
31"FPGA_OUT_SMA2_LED_RED_N";
32"LED_DATOUT2";
33"LED_DATOUT3";
34"LED_DATOUT1";
35"LED_DATOUT0";
36"FPGA_USR_LED1";
37"FPGA_OUT_GPS_LED_GREEN_N";
38"FPGA_OUT_GPS_LED_BLUE_N";
39"FPGA_OUT_SMA4_LED_RED_N";
40"FPGA_OUT_MUX1_SEL";
41"FPGA_OUT_MUX2_SEL";
42"FPGA_OUT_MUX3_SEL";
43"SMA4_SIG_OUT_BF_EN_N";
44"SMA4_SIG_IN_BF_EN_N";
45"FPGA_OUT_SMA1_LED_BLUE_N";
46"FPGA_OUT_SMA1_LED_GREEN_N";
47"FPGA_OUT_SMA1_LED_RED_N";
48"FPGA_OUT_SMA2_LED_BLUE_N";
49"FPGA_OUT_SMA2_LED_GREEN_N";
50"FPGA_USR_LED0";
51"FPGA_OUT_SMA3_LED_BLUE_N";
52"FPGA_OUT_SMA3_LED_GREEN_N";
53"FPGA_OUT_SMA3_LED_RED_N";
54"FPGA_OUT_SMA4_LED_BLUE_N";
55"FPGA_OUT_SMA4_LED_GREEN_N";
56"FPGA_OUT_GPS_LED_RED_N";
57"IO_L23N_16";
58"IO_L23P_16";
59"IO_L22N_16";
60"IO_L22P_16";
61"IO_L24N_16";
62"IO_L24P_16";
63"FPGA_BRD_REV0";
64"FPGA_OUT_BNO080_RST_N";
65"FPGA_IN_BNO080_INT_N";
%"XC7A200T_2FBG484C_FBG484"
"3","(-9150,7450)","0","pld","I228";
;
$LOCATION"U24"
CDS_LOCATION"U24"
$SEC"3"
CDS_SEC"3"
VALUE"XC7A100T-1FGG484I"
CLS_PN"G240-10069-01"
CDS_LIB"pld"
CDS_LMAN_SYM_OUTLINE"0,0,3000,-5400";
"IO_L1P_T0_AD0P_15"
$PN"H13"40;
"IO_L1P_T0_16"
$PN"F13"45;
"IO_L1N_T0_AD0N_15"
$PN"G13"41;
"IO_L1N_T0_16"
$PN"F14"46;
"IO_L8P_T1_AD10P_15"
$PN"H20"4;
"IO_L8P_T1_16"
$PN"C13"34;
"IO_L8N_T1_AD10N_15"
$PN"G20"8;
"IO_L8N_T1_16"
$PN"B13"35;
"IO_L7P_T1_AD2P_15"
$PN"J22"6;
"IO_L7P_T1_16"
$PN"B15"0;
"IO_L7N_T1_AD2N_15"
$PN"H22"5;
"IO_L7N_T1_16"
$PN"B16"0;
"IO_L6P_T0_16"
$PN"D14"32;
"IO_L6P_T0_15"
$PN"H17"0;
"IO_L6N_T0_VREF_16"
$PN"D15"33;
"IO_L6N_T0_VREF_15"
$PN"H18"0;
"IO_L5P_T0_AD9P_15"
$PN"J15"18;
"IO_L5P_T0_16"
$PN"E16"0;
"IO_L5N_T0_AD9N_15"
$PN"H15"9;
"IO_L5N_T0_16"
$PN"D16"0;
"IO_L4P_T0_16"
$PN"E13"31;
"IO_L4P_T0_15"
$PN"G17"0;
"IO_L4N_T0_16"
$PN"E14"0;
"IO_L4N_T0_15"
$PN"G18"0;
"IO_L3P_T0_DQS_AD1P_15"
$PN"J14"44;
"IO_L3P_T0_DQS_16"
$PN"C14"48;
"IO_L3N_T0_DQS_AD1N_15"
$PN"H14"43;
"IO_L3N_T0_DQS_16"
$PN"C15"49;
"IO_L2P_T0_AD8P_15"
$PN"G15"42;
"IO_L2P_T0_16"
$PN"F16"47;
"IO_L2N_T0_AD8N_15"
$PN"G16"0;
"IO_L2N_T0_16"
$PN"E17"0;
"IO_L16P_T2_A28_15"
$PN"M18"11;
"IO_L16P_T2_16"
$PN"B20"38;
"IO_L16N_T2_A27_15"
$PN"L18"0;
"IO_L16N_T2_16"
$PN"A20"37;
"IO_L24P_T3_RS1_15"
$PN"M15"25;
"IO_L24P_T3_16"
$PN"G21"62;
"IO_L24N_T3_RS0_15"
$PN"M16"26;
"IO_L24N_T3_16"
$PN"G22"61;
"IO_L23P_T3_FOE_B_15"
$PN"L16"0;
"IO_L23P_T3_16"
$PN"E21"58;
"IO_L23N_T3_FWE_B_15"
$PN"K16"24;
"IO_L23N_T3_16"
$PN"D21"57;
"IO_L22P_T3_A17_15"
$PN"L14"65;
"IO_L22P_T3_16"
$PN"E22"60;
"IO_L22N_T3_A16_15"
$PN"L15"23;
"IO_L22N_T3_16"
$PN"D22"59;
"IO_L21P_T3_DQS_16"
$PN"B21"29;
"IO_L21P_T3_DQS_15"
$PN"K17"0;
"IO_L21N_T3_DQS_A18_15"
$PN"J17"64;
"IO_L21N_T3_DQS_16"
$PN"A21"30;
"IO_L20P_T3_A20_15"
$PN"M13"20;
"IO_L20P_T3_16"
$PN"C22"27;
"IO_L20N_T3_A19_15"
$PN"L13"22;
"IO_L20N_T3_16"
$PN"B22"28;
"IO_L19P_T3_A22_15"
$PN"K13"17;
"IO_L19P_T3_16"
$PN"D20"0;
"IO_L19N_T3_VREF_16"
$PN"C20"0;
"IO_L19N_T3_A21_VREF_15"
$PN"K14"21;
"IO_L18P_T2_A24_15"
$PN"N20"63;
"IO_L18P_T2_16"
$PN"F19"0;
"IO_L18N_T2_A23_15"
$PN"M20"0;
"IO_L18N_T2_16"
$PN"F20"0;
"IO_L17P_T2_A26_15"
$PN"N18"12;
"IO_L17P_T2_16"
$PN"A18"56;
"IO_L17N_T2_A25_15"
$PN"N19"13;
"IO_L17N_T2_16"
$PN"A19"0;
"IO_L9P_T1_DQS_AD3P_15"
$PN"K21"7;
"IO_L9P_T1_DQS_16"
$PN"A15"0;
"IO_L9N_T1_DQS_AD3N_15"
$PN"K22"19;
"IO_L9N_T1_DQS_16"
$PN"A16"0;
"IO_L15P_T2_DQS_16"
$PN"F18"39;
"IO_L15P_T2_DQS_15"
$PN"N22"1;
"IO_L15N_T2_DQS_ADV_B_15"
$PN"M22"2;
"IO_L15N_T2_DQS_16"
$PN"E18"0;
"IO_L14P_T2_SRCC_16"
$PN"E19"54;
"IO_L14P_T2_SRCC_15"
$PN"L19"0;
"IO_L14N_T2_SRCC_16"
$PN"D19"55;
"IO_L14N_T2_SRCC_15"
$PN"L20"0;
"IO_L13P_T2_MRCC_16"
$PN"C18"53;
"IO_L13P_T2_MRCC_15"
$PN"K18"0;
"IO_L13N_T2_MRCC_16"
$PN"C19"0;
"IO_L13N_T2_MRCC_15"
$PN"K19"0;
"IO_L12P_T1_MRCC_16"
$PN"D17"51;
"IO_L12P_T1_MRCC_15"
$PN"J19"15;
"IO_L12N_T1_MRCC_16"
$PN"C17"52;
"IO_L12N_T1_MRCC_15"
$PN"H19"16;
"IO_L11P_T1_SRCC_16"
$PN"B17"0;
"IO_L11P_T1_SRCC_15"
$PN"J20"14;
"IO_L11N_T1_SRCC_16"
$PN"B18"0;
"IO_L11N_T1_SRCC_15"
$PN"J21"0;
"IO_L10P_T1_AD11P_15"
$PN"M21"3;
"IO_L10P_T1_16"
$PN"A13"36;
"IO_L10N_T1_AD11N_15"
$PN"L21"10;
"IO_L10N_T1_16"
$PN"A14"50;
"IO_25_16"
$PN"F21"0;
"IO_25_15"
$PN"M17"0;
"IO_0_16"
$PN"F15"0;
"IO_0_15"
$PN"J16"0;
END.
